(kicad_pcb
	(version 20260206)
	(generator "pcbnew")
	(generator_version "10.0")
	(general
		(thickness 1.6)
		(legacy_teardrops no)
	)
	(paper "A4")
	(title_block
		(title "v1-chassis-manager — T6M_CM_d_v01_1031_1645.brd")
		(comment 1 "Open CloudServer (Microsoft) / footprints 1029-1038 of 2512")
	)
	(layers
		(0 "F.Cu" signal "TOP")
		(4 "In1.Cu" signal "GND1")
		(6 "In2.Cu" signal "IN1")
		(8 "In3.Cu" signal "VCC1")
		(10 "In4.Cu" signal "VCC2")
		(12 "In5.Cu" signal "GND2")
		(14 "In6.Cu" signal "IN2")
		(16 "In7.Cu" signal "IN3")
		(18 "In8.Cu" signal "GND3")
		(2 "B.Cu" signal "BOTTOM")
		(9 "F.Adhes" user "F.Adhesive")
		(11 "B.Adhes" user "B.Adhesive")
		(13 "F.Paste" user "Package Geometry/Pastemask Top")
		(15 "B.Paste" user "Package Geometry/Pastemask Bottom")
		(5 "F.SilkS" user "Ref Des/Silkscreen Top")
		(7 "B.SilkS" user "Ref Des/Silkscreen Bottom")
		(1 "F.Mask" user "Board Geometry/Soldermask Top")
		(3 "B.Mask" user "Board Geometry/Soldermask Bottom")
		(17 "Dwgs.User" user "User.Drawings")
		(19 "Cmts.User" user "User.Comments")
		(21 "Eco1.User" user "User.Eco1")
		(23 "Eco2.User" user "User.Eco2")
		(25 "Edge.Cuts" user "Board Geometry/Outline")
		(27 "Margin" user)
		(31 "F.CrtYd" user "Package Geometry/Place Bound Top")
		(29 "B.CrtYd" user "Package Geometry/Place Bound Bottom")
		(35 "F.Fab" user "Ref Des/Assembly Top")
		(33 "B.Fab" user "Ref Des/Assembly Bottom")
	)
	(footprint ""
		(layer "F.Cu")
		(at 185.817764 -115.367562 90)
		(property "Reference" "R1027"
			(at -4.22275 -0.987806 0)
			(unlocked yes)
			(layer "F.SilkS")
			(effects
				(font
					(size 0.7874 0.5842)
					(thickness 0.1524)
				)
				(justify left)
			)
		)
		(property "Value" ""
			(at 0 0 90)
			(layer "F.Fab")
			(effects
				(font
					(size 1.27 1.27)
				)
			)
		)
		(duplicate_pad_numbers_are_jumpers no)
		(fp_line
			(start 0.7874 -0.4064)
			(end 0.7874 0.4064)
			(stroke
				(width 0.1524)
				(type default)
			)
			(layer "F.SilkS")
		)
		(fp_line
			(start -0.7874 -0.4064)
			(end 0.7874 -0.4064)
			(stroke
				(width 0.1524)
				(type default)
			)
			(layer "F.SilkS")
		)
		(fp_line
			(start 0.7874 0.4064)
			(end -0.7874 0.4064)
			(stroke
				(width 0.1524)
				(type default)
			)
			(layer "F.SilkS")
		)
		(fp_line
			(start -0.7874 0.4064)
			(end -0.7874 -0.4064)
			(stroke
				(width 0.1524)
				(type default)
			)
			(layer "F.SilkS")
		)
		(fp_poly
			(pts
				(xy -0.508 0.2794) (xy -0.508 0.2286) (xy -0.635 0.2286) (xy -0.635 -0.254) (xy -0.5334 -0.254)
				(xy -0.5334 -0.2794) (xy 0.5334 -0.2794) (xy 0.5334 -0.254) (xy 0.635 -0.254) (xy 0.635 0.254) (xy 0.5334 0.254)
				(xy 0.5334 0.2794)
			)
			(stroke
				(width 0)
				(type default)
			)
			(fill no)
			(layer "F.CrtYd")
		)
		(pad "1" smd rect
			(at 0.40005 0 90)
			(size 0.4572 0.508)
			(layers "F.Cu" "F.Mask" "F.Paste")
			(net "PWRGD_NODE1_P12V_PG")
		)
		(pad "2" smd rect
			(at -0.40005 0 90)
			(size 0.4572 0.508)
			(layers "F.Cu" "F.Mask" "F.Paste")
			(net "PWRGD_NODE1_P12V_PG_R")
		)
	)
	(footprint ""
		(layer "F.Cu")
		(at 160.054798 -161.370518 90)
		(property "Reference" "R574"
			(at -8.066278 17.651476 90)
			(unlocked yes)
			(layer "F.SilkS")
			(effects
				(font
					(size 0.7874 0.5842)
					(thickness 0.1524)
				)
				(justify left)
			)
		)
		(property "Value" ""
			(at 0 0 90)
			(layer "F.Fab")
			(effects
				(font
					(size 1.27 1.27)
				)
			)
		)
		(duplicate_pad_numbers_are_jumpers no)
		(fp_line
			(start 0.7874 -0.4064)
			(end 0.7874 0.4064)
			(stroke
				(width 0.1524)
				(type default)
			)
			(layer "F.SilkS")
		)
		(fp_line
			(start -0.7874 -0.4064)
			(end 0.7874 -0.4064)
			(stroke
				(width 0.1524)
				(type default)
			)
			(layer "F.SilkS")
		)
		(fp_line
			(start 0.7874 0.4064)
			(end -0.7874 0.4064)
			(stroke
				(width 0.1524)
				(type default)
			)
			(layer "F.SilkS")
		)
		(fp_line
			(start -0.7874 0.4064)
			(end -0.7874 -0.4064)
			(stroke
				(width 0.1524)
				(type default)
			)
			(layer "F.SilkS")
		)
		(fp_poly
			(pts
				(xy -0.508 0.2794) (xy -0.508 0.2286) (xy -0.635 0.2286) (xy -0.635 -0.254) (xy -0.5334 -0.254)
				(xy -0.5334 -0.2794) (xy 0.5334 -0.2794) (xy 0.5334 -0.254) (xy 0.635 -0.254) (xy 0.635 0.254) (xy 0.5334 0.254)
				(xy 0.5334 0.2794)
			)
			(stroke
				(width 0)
				(type default)
			)
			(fill no)
			(layer "F.CrtYd")
		)
		(pad "1" smd rect
			(at 0.40005 0 90)
			(size 0.4572 0.508)
			(layers "F.Cu" "F.Mask" "F.Paste")
			(net "P3V3_NODE1")
		)
		(pad "2" smd rect
			(at -0.40005 0 90)
			(size 0.4572 0.508)
			(layers "F.Cu" "F.Mask" "F.Paste")
			(net "LAN2_NC_SI_TDX0")
		)
	)
	(footprint ""
		(layer "F.Cu")
		(at 63.832486 -121.044462 -90)
		(property "Reference" "R327"
			(at 6.142736 -8.268716 90)
			(unlocked yes)
			(layer "F.SilkS")
			(effects
				(font
					(size 0.7874 0.5842)
					(thickness 0.1524)
				)
				(justify left)
			)
		)
		(property "Value" ""
			(at 0 0 270)
			(layer "F.Fab")
			(effects
				(font
					(size 1.27 1.27)
				)
			)
		)
		(duplicate_pad_numbers_are_jumpers no)
		(fp_line
			(start -0.7874 0.4064)
			(end -0.7874 -0.4064)
			(stroke
				(width 0.1524)
				(type default)
			)
			(layer "F.SilkS")
		)
		(fp_line
			(start 0.7874 0.4064)
			(end -0.7874 0.4064)
			(stroke
				(width 0.1524)
				(type default)
			)
			(layer "F.SilkS")
		)
		(fp_line
			(start -0.7874 -0.4064)
			(end 0.7874 -0.4064)
			(stroke
				(width 0.1524)
				(type default)
			)
			(layer "F.SilkS")
		)
		(fp_line
			(start 0.7874 -0.4064)
			(end 0.7874 0.4064)
			(stroke
				(width 0.1524)
				(type default)
			)
			(layer "F.SilkS")
		)
		(fp_poly
			(pts
				(xy -0.508 0.2794) (xy -0.508 0.2286) (xy -0.635 0.2286) (xy -0.635 -0.254) (xy -0.5334 -0.254)
				(xy -0.5334 -0.2794) (xy 0.5334 -0.2794) (xy 0.5334 -0.254) (xy 0.635 -0.254) (xy 0.635 0.254) (xy 0.5334 0.254)
				(xy 0.5334 0.2794)
			)
			(stroke
				(width 0)
				(type default)
			)
			(fill no)
			(layer "F.CrtYd")
		)
		(pad "1" smd rect
			(at 0.40005 0 270)
			(size 0.4572 0.508)
			(layers "F.Cu" "F.Mask" "F.Paste")
			(net "P3V3_NODE1")
		)
		(pad "2" smd rect
			(at -0.40005 0 270)
			(size 0.4572 0.508)
			(layers "F.Cu" "F.Mask" "F.Paste")
			(net "BMC_ROMA11")
		)
	)
	(footprint ""
		(layer "F.Cu")
		(at 171.685458 -12.474194 90)
		(property "Reference" "R1200"
			(at -0.981202 2.072132 90)
			(unlocked yes)
			(layer "F.SilkS")
			(effects
				(font
					(size 0.7874 0.5842)
					(thickness 0.1524)
				)
				(justify left)
			)
		)
		(property "Value" ""
			(at 0 0 90)
			(layer "F.Fab")
			(effects
				(font
					(size 1.27 1.27)
				)
			)
		)
		(duplicate_pad_numbers_are_jumpers no)
		(fp_line
			(start 0.7874 -0.4064)
			(end 0.7874 0.4064)
			(stroke
				(width 0.1524)
				(type default)
			)
			(layer "F.SilkS")
		)
		(fp_line
			(start -0.7874 -0.4064)
			(end 0.7874 -0.4064)
			(stroke
				(width 0.1524)
				(type default)
			)
			(layer "F.SilkS")
		)
		(fp_line
			(start 0.7874 0.4064)
			(end -0.7874 0.4064)
			(stroke
				(width 0.1524)
				(type default)
			)
			(layer "F.SilkS")
		)
		(fp_line
			(start -0.7874 0.4064)
			(end -0.7874 -0.4064)
			(stroke
				(width 0.1524)
				(type default)
			)
			(layer "F.SilkS")
		)
		(fp_poly
			(pts
				(xy -0.508 0.2794) (xy -0.508 0.2286) (xy -0.635 0.2286) (xy -0.635 -0.254) (xy -0.5334 -0.254)
				(xy -0.5334 -0.2794) (xy 0.5334 -0.2794) (xy 0.5334 -0.254) (xy 0.635 -0.254) (xy 0.635 0.254) (xy 0.5334 0.254)
				(xy 0.5334 0.2794)
			)
			(stroke
				(width 0)
				(type default)
			)
			(fill no)
			(layer "F.CrtYd")
		)
		(pad "1" smd rect
			(at 0.40005 0 90)
			(size 0.4572 0.508)
			(layers "F.Cu" "F.Mask" "F.Paste")
			(net "SIO_JTAG_CPLD3_TCK")
		)
		(pad "2" smd rect
			(at -0.40005 0 90)
			(size 0.4572 0.508)
			(layers "F.Cu" "F.Mask" "F.Paste")
			(net "JTAG_CPLD3_TCK")
		)
	)
	(footprint ""
		(layer "F.Cu")
		(at 82.563462 -153.762456 180)
		(property "Reference" "PR4"
			(at -1.147318 -0.315468 0)
			(unlocked yes)
			(layer "F.SilkS")
			(effects
				(font
					(size 0.7874 0.5842)
					(thickness 0.1524)
				)
				(justify left)
			)
		)
		(property "Value" ""
			(at 0 0 180)
			(layer "F.Fab")
			(effects
				(font
					(size 1.27 1.27)
				)
			)
		)
		(duplicate_pad_numbers_are_jumpers no)
		(fp_line
			(start 0.7874 0.4064)
			(end -0.7874 0.4064)
			(stroke
				(width 0.1524)
				(type default)
			)
			(layer "F.SilkS")
		)
		(fp_line
			(start 0.7874 -0.4064)
			(end 0.7874 0.4064)
			(stroke
				(width 0.1524)
				(type default)
			)
			(layer "F.SilkS")
		)
		(fp_line
			(start -0.7874 0.4064)
			(end -0.7874 -0.4064)
			(stroke
				(width 0.1524)
				(type default)
			)
			(layer "F.SilkS")
		)
		(fp_line
			(start -0.7874 -0.4064)
			(end 0.7874 -0.4064)
			(stroke
				(width 0.1524)
				(type default)
			)
			(layer "F.SilkS")
		)
		(fp_poly
			(pts
				(xy -0.508 0.2794) (xy -0.508 0.2286) (xy -0.635 0.2286) (xy -0.635 -0.254) (xy -0.5334 -0.254)
				(xy -0.5334 -0.2794) (xy 0.5334 -0.2794) (xy 0.5334 -0.254) (xy 0.635 -0.254) (xy 0.635 0.254) (xy 0.5334 0.254)
				(xy 0.5334 0.2794)
			)
			(stroke
				(width 0)
				(type default)
			)
			(fill no)
			(layer "F.CrtYd")
		)
		(pad "1" smd rect
			(at 0.40005 0 180)
			(size 0.4572 0.508)
			(layers "F.Cu" "F.Mask" "F.Paste")
			(net "P5V_STB_NODE1_FB")
		)
		(pad "2" smd rect
			(at -0.40005 0 180)
			(size 0.4572 0.508)
			(layers "F.Cu" "F.Mask" "F.Paste")
			(net "GND")
		)
	)
	(footprint ""
		(layer "F.Cu")
		(at 184.7596 -176.4792 180)
		(property "Reference" "R1314"
			(at -9.9568 -17.45107 0)
			(unlocked yes)
			(layer "F.SilkS")
			(effects
				(font
					(size 0.7874 0.5842)
					(thickness 0.1524)
				)
				(justify left)
			)
		)
		(property "Value" ""
			(at 0 0 180)
			(layer "F.Fab")
			(effects
				(font
					(size 1.27 1.27)
				)
			)
		)
		(duplicate_pad_numbers_are_jumpers no)
		(fp_line
			(start 0.7874 0.4064)
			(end -0.7874 0.4064)
			(stroke
				(width 0.1524)
				(type default)
			)
			(layer "F.SilkS")
		)
		(fp_line
			(start 0.7874 -0.4064)
			(end 0.7874 0.4064)
			(stroke
				(width 0.1524)
				(type default)
			)
			(layer "F.SilkS")
		)
		(fp_line
			(start -0.7874 0.4064)
			(end -0.7874 -0.4064)
			(stroke
				(width 0.1524)
				(type default)
			)
			(layer "F.SilkS")
		)
		(fp_line
			(start -0.7874 -0.4064)
			(end 0.7874 -0.4064)
			(stroke
				(width 0.1524)
				(type default)
			)
			(layer "F.SilkS")
		)
		(fp_poly
			(pts
				(xy -0.508 0.2794) (xy -0.508 0.2286) (xy -0.635 0.2286) (xy -0.635 -0.254) (xy -0.5334 -0.254)
				(xy -0.5334 -0.2794) (xy 0.5334 -0.2794) (xy 0.5334 -0.254) (xy 0.635 -0.254) (xy 0.635 0.254) (xy 0.5334 0.254)
				(xy 0.5334 0.2794)
			)
			(stroke
				(width 0)
				(type default)
			)
			(fill no)
			(layer "F.CrtYd")
		)
		(pad "1" smd rect
			(at 0.40005 0 180)
			(size 0.4572 0.508)
			(layers "F.Cu" "F.Mask" "F.Paste")
			(net "POWER_SW2_PWR_CTR_12V")
		)
		(pad "2" smd rect
			(at -0.40005 0 180)
			(size 0.4572 0.508)
			(layers "F.Cu" "F.Mask" "F.Paste")
			(net "POWER_SW2_PWR_CTR_12V_R")
		)
	)
	(footprint ""
		(layer "F.Cu")
		(at 142.22476 -188.126624 90)
		(property "Reference" "C765"
			(at 5.519674 -0.636016 90)
			(unlocked yes)
			(layer "F.SilkS")
			(effects
				(font
					(size 0.7874 0.5842)
					(thickness 0.1524)
				)
				(justify left)
			)
		)
		(property "Value" ""
			(at 0 0 90)
			(layer "F.Fab")
			(effects
				(font
					(size 1.27 1.27)
				)
			)
		)
		(duplicate_pad_numbers_are_jumpers no)
		(fp_line
			(start 0.7874 -0.4064)
			(end 0.7874 0.4064)
			(stroke
				(width 0.1524)
				(type default)
			)
			(layer "F.SilkS")
		)
		(fp_line
			(start -0.7874 -0.4064)
			(end 0.7874 -0.4064)
			(stroke
				(width 0.1524)
				(type default)
			)
			(layer "F.SilkS")
		)
		(fp_line
			(start 0 0.381)
			(end 0 -0.381)
			(stroke
				(width 0.1524)
				(type default)
			)
			(layer "F.SilkS")
		)
		(fp_line
			(start 0.7874 0.4064)
			(end -0.7874 0.4064)
			(stroke
				(width 0.1524)
				(type default)
			)
			(layer "F.SilkS")
		)
		(fp_line
			(start -0.7874 0.4064)
			(end -0.7874 -0.4064)
			(stroke
				(width 0.1524)
				(type default)
			)
			(layer "F.SilkS")
		)
		(fp_poly
			(pts
				(xy -0.5334 0.254) (xy -0.635 0.254) (xy -0.635 0.2286) (xy -0.635 -0.254) (xy -0.5334 -0.254) (xy -0.5334 -0.2794)
				(xy 0.5334 -0.2794) (xy 0.5334 -0.254) (xy 0.635 -0.254) (xy 0.635 0.254) (xy 0.5334 0.254) (xy 0.5334 0.2794)
				(xy -0.508 0.2794) (xy -0.5334 0.2794)
			)
			(stroke
				(width 0)
				(type default)
			)
			(fill no)
			(layer "F.CrtYd")
		)
		(pad "1" smd rect
			(at 0.40005 0 90)
			(size 0.4572 0.508)
			(layers "F.Cu" "F.Mask" "F.Paste")
			(net "UART_T12_NODE4_TXD_R")
		)
		(pad "2" smd rect
			(at -0.40005 0 90)
			(size 0.4572 0.508)
			(layers "F.Cu" "F.Mask" "F.Paste")
			(net "GND")
		)
	)
	(footprint ""
		(layer "F.Cu")
		(at 10.566146 -11.613896 -90)
		(property "Reference" "R216"
			(at 0.984758 4.681982 90)
			(unlocked yes)
			(layer "F.SilkS")
			(effects
				(font
					(size 0.7874 0.5842)
					(thickness 0.1524)
				)
				(justify left)
			)
		)
		(property "Value" ""
			(at 0 0 270)
			(layer "F.Fab")
			(effects
				(font
					(size 1.27 1.27)
				)
			)
		)
		(duplicate_pad_numbers_are_jumpers no)
		(fp_line
			(start -0.7874 0.4064)
			(end -0.7874 -0.4064)
			(stroke
				(width 0.1524)
				(type default)
			)
			(layer "F.SilkS")
		)
		(fp_line
			(start 0.7874 0.4064)
			(end -0.7874 0.4064)
			(stroke
				(width 0.1524)
				(type default)
			)
			(layer "F.SilkS")
		)
		(fp_line
			(start -0.7874 -0.4064)
			(end 0.7874 -0.4064)
			(stroke
				(width 0.1524)
				(type default)
			)
			(layer "F.SilkS")
		)
		(fp_line
			(start 0.7874 -0.4064)
			(end 0.7874 0.4064)
			(stroke
				(width 0.1524)
				(type default)
			)
			(layer "F.SilkS")
		)
		(fp_poly
			(pts
				(xy -0.508 0.2794) (xy -0.508 0.2286) (xy -0.635 0.2286) (xy -0.635 -0.254) (xy -0.5334 -0.254)
				(xy -0.5334 -0.2794) (xy 0.5334 -0.2794) (xy 0.5334 -0.254) (xy 0.635 -0.254) (xy 0.635 0.254) (xy 0.5334 0.254)
				(xy 0.5334 0.2794)
			)
			(stroke
				(width 0)
				(type default)
			)
			(fill no)
			(layer "F.CrtYd")
		)
		(pad "1" smd rect
			(at 0.40005 0 270)
			(size 0.4572 0.508)
			(layers "F.Cu" "F.Mask" "F.Paste")
			(net "PV_VDDR_NODE1_VREF_R")
		)
		(pad "2" smd rect
			(at -0.40005 0 270)
			(size 0.4572 0.508)
			(layers "F.Cu" "F.Mask" "F.Paste")
			(net "PV_VDDR_NODE1_VREF_LM321")
		)
	)
	(footprint ""
		(layer "F.Cu")
		(at 118.37797 -25.081738 180)
		(property "Reference" "C855"
			(at 0.43688 -2.01168 0)
			(unlocked yes)
			(layer "F.SilkS")
			(effects
				(font
					(size 0.7874 0.5842)
					(thickness 0.1524)
				)
				(justify left)
			)
		)
		(property "Value" ""
			(at 0 0 180)
			(layer "F.Fab")
			(effects
				(font
					(size 1.27 1.27)
				)
			)
		)
		(duplicate_pad_numbers_are_jumpers no)
		(fp_line
			(start 0.7874 0.4064)
			(end -0.7874 0.4064)
			(stroke
				(width 0.1524)
				(type default)
			)
			(layer "F.SilkS")
		)
		(fp_line
			(start 0.7874 -0.4064)
			(end 0.7874 0.4064)
			(stroke
				(width 0.1524)
				(type default)
			)
			(layer "F.SilkS")
		)
		(fp_line
			(start 0 0.381)
			(end 0 -0.381)
			(stroke
				(width 0.1524)
				(type default)
			)
			(layer "F.SilkS")
		)
		(fp_line
			(start -0.7874 0.4064)
			(end -0.7874 -0.4064)
			(stroke
				(width 0.1524)
				(type default)
			)
			(layer "F.SilkS")
		)
		(fp_line
			(start -0.7874 -0.4064)
			(end 0.7874 -0.4064)
			(stroke
				(width 0.1524)
				(type default)
			)
			(layer "F.SilkS")
		)
		(fp_poly
			(pts
				(xy -0.5334 0.254) (xy -0.635 0.254) (xy -0.635 0.2286) (xy -0.635 -0.254) (xy -0.5334 -0.254) (xy -0.5334 -0.2794)
				(xy 0.5334 -0.2794) (xy 0.5334 -0.254) (xy 0.635 -0.254) (xy 0.635 0.254) (xy 0.5334 0.254) (xy 0.5334 0.2794)
				(xy -0.508 0.2794) (xy -0.5334 0.2794)
			)
			(stroke
				(width 0)
				(type default)
			)
			(fill no)
			(layer "F.CrtYd")
		)
		(pad "1" smd rect
			(at 0.40005 0 180)
			(size 0.4572 0.508)
			(layers "F.Cu" "F.Mask" "F.Paste")
			(net "PV_VTT_DDR_NODE1_REFIN")
		)
		(pad "2" smd rect
			(at -0.40005 0 180)
			(size 0.4572 0.508)
			(layers "F.Cu" "F.Mask" "F.Paste")
			(net "GND")
		)
	)
	(footprint ""
		(layer "F.Cu")
		(at 167.80764 -188.19749 -90)
		(property "Reference" "R841"
			(at -0.95631 0.21717 90)
			(unlocked yes)
			(layer "F.SilkS")
			(effects
				(font
					(size 0.7874 0.5842)
					(thickness 0.1524)
				)
				(justify left)
			)
		)
		(property "Value" ""
			(at 0 0 270)
			(layer "F.Fab")
			(effects
				(font
					(size 1.27 1.27)
				)
			)
		)
		(duplicate_pad_numbers_are_jumpers no)
		(fp_line
			(start -0.7874 0.4064)
			(end -0.7874 -0.4064)
			(stroke
				(width 0.1524)
				(type default)
			)
			(layer "F.SilkS")
		)
		(fp_line
			(start 0.7874 0.4064)
			(end -0.7874 0.4064)
			(stroke
				(width 0.1524)
				(type default)
			)
			(layer "F.SilkS")
		)
		(fp_line
			(start -0.7874 -0.4064)
			(end 0.7874 -0.4064)
			(stroke
				(width 0.1524)
				(type default)
			)
			(layer "F.SilkS")
		)
		(fp_line
			(start 0.7874 -0.4064)
			(end 0.7874 0.4064)
			(stroke
				(width 0.1524)
				(type default)
			)
			(layer "F.SilkS")
		)
		(fp_poly
			(pts
				(xy -0.508 0.2794) (xy -0.508 0.2286) (xy -0.635 0.2286) (xy -0.635 -0.254) (xy -0.5334 -0.254)
				(xy -0.5334 -0.2794) (xy 0.5334 -0.2794) (xy 0.5334 -0.254) (xy 0.635 -0.254) (xy 0.635 0.254) (xy 0.5334 0.254)
				(xy 0.5334 0.2794)
			)
			(stroke
				(width 0)
				(type default)
			)
			(fill no)
			(layer "F.CrtYd")
		)
		(pad "1" smd rect
			(at 0.40005 0 270)
			(size 0.4572 0.508)
			(layers "F.Cu" "F.Mask" "F.Paste")
			(net "I2C_PDB_SCL")
		)
		(pad "2" smd rect
			(at -0.40005 0 270)
			(size 0.4572 0.508)
			(layers "F.Cu" "F.Mask" "F.Paste")
			(net "I2C_PDB_R_SCL")
		)
	)
)
